(kicad_pcb
	(version 20260206)
	(generator "pcbnew")
	(generator_version "10.0")
	(general
		(thickness 1.6)
		(legacy_teardrops no)
	)
	(paper "A4")
	(title_block
		(title "03242023_DA0F0TMBIJ0_F0T_Motherboard_J_brd_V01_OCP.brd")
		(comment 1 "Grand Teton / footprint 2048 of 6105 (J3), pads 225-291 of 291")
	)
	(layers
		(0 "F.Cu" signal "TOP")
		(4 "In1.Cu" signal "GND")
		(6 "In2.Cu" signal "IN1")
		(8 "In3.Cu" signal "GND1")
		(10 "In4.Cu" signal "IN2")
		(12 "In5.Cu" signal "GND2")
		(14 "In6.Cu" signal "IN3")
		(16 "In7.Cu" signal "GND3")
		(18 "In8.Cu" signal "VCC")
		(20 "In9.Cu" signal "VCC1")
		(22 "In10.Cu" signal "GND4")
		(24 "In11.Cu" signal "IN4")
		(26 "In12.Cu" signal "GND5")
		(28 "In13.Cu" signal "IN5")
		(30 "In14.Cu" signal "GND6")
		(32 "In15.Cu" signal "IN6")
		(34 "In16.Cu" signal "GND7")
		(2 "B.Cu" signal "BOTTOM")
		(9 "F.Adhes" user "F.Adhesive")
		(11 "B.Adhes" user "B.Adhesive")
		(13 "F.Paste" user "Package Geometry/Pastemask Top")
		(15 "B.Paste" user "Package Geometry/Pastemask Bottom")
		(5 "F.SilkS" user "Ref Des/Silkscreen Top")
		(7 "B.SilkS" user "Ref Des/Silkscreen Bottom")
		(1 "F.Mask" user "Board Geometry/Soldermask Top")
		(3 "B.Mask" user "Board Geometry/Soldermask Bottom")
		(17 "Dwgs.User" user "User.Drawings")
		(19 "Cmts.User" user "User.Comments")
		(21 "Eco1.User" user "User.Eco1")
		(23 "Eco2.User" user "User.Eco2")
		(25 "Edge.Cuts" user "Board Geometry/Outline")
		(27 "Margin" user)
		(31 "F.CrtYd" user "Package Geometry/Place Bound Top")
		(29 "B.CrtYd" user "Package Geometry/Place Bound Bottom")
		(35 "F.Fab" user "Ref Des/Assembly Top")
		(33 "B.Fab" user "Ref Des/Assembly Bottom")
	)
	(footprint ""
		(layer "F.Cu")
		(at 288.305748 -258.091686)
		(property "Reference" "J3"
			(at -3.683 -81.702148 0)
			(unlocked yes)
			(layer "F.SilkS")
			(effects
				(font
					(size 0.7874 0.5842)
					(thickness 0.1524)
				)
				(justify left)
			)
		)
		(property "Value" ""
			(at 0 0 0)
			(layer "F.Fab")
			(effects
				(font
					(size 1.27 1.27)
				)
			)
		)
		(duplicate_pad_numbers_are_jumpers no)
		(pad "225" smd rect
			(at 2.050034 9.774936 270)
			(size 0.519938 1.4986)
			(layers "F.Cu" "F.Mask" "F.Paste")
			(net "M_B_CPU0_SB_CA<5>")
		)
		(pad "226" smd rect
			(at 2.050034 10.625074 270)
			(size 0.519938 1.4986)
			(layers "F.Cu" "F.Mask" "F.Paste")
			(net "GND")
		)
		(pad "227" smd rect
			(at 2.050034 11.474958 270)
			(size 0.519938 1.4986)
			(layers "F.Cu" "F.Mask" "F.Paste")
			(net "M_B_CPU0_SB_PAR")
		)
		(pad "228" smd rect
			(at 2.050034 12.325096 270)
			(size 0.519938 1.4986)
			(layers "F.Cu" "F.Mask" "F.Paste")
			(net "GND")
		)
		(pad "229" smd rect
			(at 2.050034 13.17498 270)
			(size 0.519938 1.4986)
			(layers "F.Cu" "F.Mask" "F.Paste")
			(net "M_B_CPU0_SB_CS_N<1>")
		)
		(pad "230" smd rect
			(at 2.050034 14.025118 270)
			(size 0.519938 1.4986)
			(layers "F.Cu" "F.Mask" "F.Paste")
			(net "GND")
		)
		(pad "231" smd rect
			(at 2.050034 14.875002 270)
			(size 0.519938 1.4986)
			(layers "F.Cu" "F.Mask" "F.Paste")
			(net "TP_CHB_CPU0_DIMM1_FRU_5")
		)
		(pad "232" smd rect
			(at 2.050034 15.724886 270)
			(size 0.519938 1.4986)
			(layers "F.Cu" "F.Mask" "F.Paste")
			(net "TP_CHB_CPU0_DIMM1_FRU_6")
		)
		(pad "233" smd rect
			(at 2.050034 16.575024 270)
			(size 0.519938 1.4986)
			(layers "F.Cu" "F.Mask" "F.Paste")
			(net "GND")
		)
		(pad "234" smd rect
			(at 2.050034 17.424908 270)
			(size 0.519938 1.4986)
			(layers "F.Cu" "F.Mask" "F.Paste")
			(net "M_B_CPU0_SB_CB<6>")
		)
		(pad "235" smd rect
			(at 2.050034 18.275046 270)
			(size 0.519938 1.4986)
			(layers "F.Cu" "F.Mask" "F.Paste")
			(net "GND")
		)
		(pad "236" smd rect
			(at 2.050034 19.12493 270)
			(size 0.519938 1.4986)
			(layers "F.Cu" "F.Mask" "F.Paste")
			(net "M_B_CPU0_SB_CB<7>")
		)
		(pad "237" smd rect
			(at 2.050034 19.975068 270)
			(size 0.519938 1.4986)
			(layers "F.Cu" "F.Mask" "F.Paste")
			(net "GND")
		)
		(pad "238" smd rect
			(at 2.050034 20.824952 270)
			(size 0.519938 1.4986)
			(layers "F.Cu" "F.Mask" "F.Paste")
			(net "M_B_CPU0_SB_DQS_DN<4>")
		)
		(pad "239" smd rect
			(at 2.050034 21.67509 270)
			(size 0.519938 1.4986)
			(layers "F.Cu" "F.Mask" "F.Paste")
			(net "M_B_CPU0_SB_DQS_DP<4>")
		)
		(pad "240" smd rect
			(at 2.050034 22.524974 270)
			(size 0.519938 1.4986)
			(layers "F.Cu" "F.Mask" "F.Paste")
			(net "GND")
		)
		(pad "241" smd rect
			(at 2.050034 23.375112 270)
			(size 0.519938 1.4986)
			(layers "F.Cu" "F.Mask" "F.Paste")
			(net "M_B_CPU0_SB_CB<2>")
		)
		(pad "242" smd rect
			(at 2.050034 24.224996 270)
			(size 0.519938 1.4986)
			(layers "F.Cu" "F.Mask" "F.Paste")
			(net "GND")
		)
		(pad "243" smd rect
			(at 2.050034 25.07488 270)
			(size 0.519938 1.4986)
			(layers "F.Cu" "F.Mask" "F.Paste")
			(net "M_B_CPU0_SB_CB<3>")
		)
		(pad "244" smd rect
			(at 2.050034 25.925018 270)
			(size 0.519938 1.4986)
			(layers "F.Cu" "F.Mask" "F.Paste")
			(net "GND")
		)
		(pad "245" smd rect
			(at 2.050034 26.774902 270)
			(size 0.519938 1.4986)
			(layers "F.Cu" "F.Mask" "F.Paste")
			(net "M_B_CPU0_SB_DQ<2>")
		)
		(pad "246" smd rect
			(at 2.050034 27.62504 270)
			(size 0.519938 1.4986)
			(layers "F.Cu" "F.Mask" "F.Paste")
			(net "GND")
		)
		(pad "247" smd rect
			(at 2.050034 28.474924 270)
			(size 0.519938 1.4986)
			(layers "F.Cu" "F.Mask" "F.Paste")
			(net "M_B_CPU0_SB_DQ<3>")
		)
		(pad "248" smd rect
			(at 2.050034 29.325062 270)
			(size 0.519938 1.4986)
			(layers "F.Cu" "F.Mask" "F.Paste")
			(net "GND")
		)
		(pad "249" smd rect
			(at 2.050034 30.174946 270)
			(size 0.519938 1.4986)
			(layers "F.Cu" "F.Mask" "F.Paste")
			(net "M_B_CPU0_SB_DQS_DN<5>")
		)
		(pad "250" smd rect
			(at 2.050034 31.025084 270)
			(size 0.519938 1.4986)
			(layers "F.Cu" "F.Mask" "F.Paste")
			(net "M_B_CPU0_SB_DQS_DP<5>")
		)
		(pad "251" smd rect
			(at 2.050034 31.874968 270)
			(size 0.519938 1.4986)
			(layers "F.Cu" "F.Mask" "F.Paste")
			(net "GND")
		)
		(pad "252" smd rect
			(at 2.050034 32.725106 270)
			(size 0.519938 1.4986)
			(layers "F.Cu" "F.Mask" "F.Paste")
			(net "M_B_CPU0_SB_DQ<6>")
		)
		(pad "253" smd rect
			(at 2.050034 33.57499 270)
			(size 0.519938 1.4986)
			(layers "F.Cu" "F.Mask" "F.Paste")
			(net "GND")
		)
		(pad "254" smd rect
			(at 2.050034 34.425128 270)
			(size 0.519938 1.4986)
			(layers "F.Cu" "F.Mask" "F.Paste")
			(net "M_B_CPU0_SB_DQ<7>")
		)
		(pad "255" smd rect
			(at 2.050034 35.275012 270)
			(size 0.519938 1.4986)
			(layers "F.Cu" "F.Mask" "F.Paste")
			(net "GND")
		)
		(pad "256" smd rect
			(at 2.050034 36.124896 270)
			(size 0.519938 1.4986)
			(layers "F.Cu" "F.Mask" "F.Paste")
			(net "M_B_CPU0_SB_DQ<10>")
		)
		(pad "257" smd rect
			(at 2.050034 36.975034 270)
			(size 0.519938 1.4986)
			(layers "F.Cu" "F.Mask" "F.Paste")
			(net "GND")
		)
		(pad "258" smd rect
			(at 2.050034 37.824918 270)
			(size 0.519938 1.4986)
			(layers "F.Cu" "F.Mask" "F.Paste")
			(net "M_B_CPU0_SB_DQ<11>")
		)
		(pad "259" smd rect
			(at 2.050034 38.675056 270)
			(size 0.519938 1.4986)
			(layers "F.Cu" "F.Mask" "F.Paste")
			(net "GND")
		)
		(pad "260" smd rect
			(at 2.050034 39.52494 270)
			(size 0.519938 1.4986)
			(layers "F.Cu" "F.Mask" "F.Paste")
			(net "M_B_CPU0_SB_DQS_DN<6>")
		)
		(pad "261" smd rect
			(at 2.050034 40.375078 270)
			(size 0.519938 1.4986)
			(layers "F.Cu" "F.Mask" "F.Paste")
			(net "M_B_CPU0_SB_DQS_DP<6>")
		)
		(pad "262" smd rect
			(at 2.050034 41.224962 270)
			(size 0.519938 1.4986)
			(layers "F.Cu" "F.Mask" "F.Paste")
			(net "GND")
		)
		(pad "263" smd rect
			(at 2.050034 42.0751 270)
			(size 0.519938 1.4986)
			(layers "F.Cu" "F.Mask" "F.Paste")
			(net "M_B_CPU0_SB_DQ<14>")
		)
		(pad "264" smd rect
			(at 2.050034 42.924984 270)
			(size 0.519938 1.4986)
			(layers "F.Cu" "F.Mask" "F.Paste")
			(net "GND")
		)
		(pad "265" smd rect
			(at 2.050034 43.775122 270)
			(size 0.519938 1.4986)
			(layers "F.Cu" "F.Mask" "F.Paste")
			(net "M_B_CPU0_SB_DQ<15>")
		)
		(pad "266" smd rect
			(at 2.050034 44.625006 270)
			(size 0.519938 1.4986)
			(layers "F.Cu" "F.Mask" "F.Paste")
			(net "GND")
		)
		(pad "267" smd rect
			(at 2.050034 45.47489 270)
			(size 0.519938 1.4986)
			(layers "F.Cu" "F.Mask" "F.Paste")
			(net "M_B_CPU0_SB_DQ<18>")
		)
		(pad "268" smd rect
			(at 2.050034 46.325028 270)
			(size 0.519938 1.4986)
			(layers "F.Cu" "F.Mask" "F.Paste")
			(net "GND")
		)
		(pad "269" smd rect
			(at 2.050034 47.174912 270)
			(size 0.519938 1.4986)
			(layers "F.Cu" "F.Mask" "F.Paste")
			(net "M_B_CPU0_SB_DQ<19>")
		)
		(pad "270" smd rect
			(at 2.050034 48.02505 270)
			(size 0.519938 1.4986)
			(layers "F.Cu" "F.Mask" "F.Paste")
			(net "GND")
		)
		(pad "271" smd rect
			(at 2.050034 48.874934 270)
			(size 0.519938 1.4986)
			(layers "F.Cu" "F.Mask" "F.Paste")
			(net "M_B_CPU0_SB_DQS_DN<7>")
		)
		(pad "272" smd rect
			(at 2.050034 49.725072 270)
			(size 0.519938 1.4986)
			(layers "F.Cu" "F.Mask" "F.Paste")
			(net "M_B_CPU0_SB_DQS_DP<7>")
		)
		(pad "273" smd rect
			(at 2.050034 50.574956 270)
			(size 0.519938 1.4986)
			(layers "F.Cu" "F.Mask" "F.Paste")
			(net "GND")
		)
		(pad "274" smd rect
			(at 2.050034 51.425094 270)
			(size 0.519938 1.4986)
			(layers "F.Cu" "F.Mask" "F.Paste")
			(net "M_B_CPU0_SB_DQ<22>")
		)
		(pad "275" smd rect
			(at 2.050034 52.274978 270)
			(size 0.519938 1.4986)
			(layers "F.Cu" "F.Mask" "F.Paste")
			(net "GND")
		)
		(pad "276" smd rect
			(at 2.050034 53.125116 270)
			(size 0.519938 1.4986)
			(layers "F.Cu" "F.Mask" "F.Paste")
			(net "M_B_CPU0_SB_DQ<23>")
		)
		(pad "277" smd rect
			(at 2.050034 53.975 270)
			(size 0.519938 1.4986)
			(layers "F.Cu" "F.Mask" "F.Paste")
			(net "GND")
		)
		(pad "278" smd rect
			(at 2.050034 54.824884 270)
			(size 0.519938 1.4986)
			(layers "F.Cu" "F.Mask" "F.Paste")
			(net "M_B_CPU0_SB_DQ<26>")
		)
		(pad "279" smd rect
			(at 2.050034 55.675022 270)
			(size 0.519938 1.4986)
			(layers "F.Cu" "F.Mask" "F.Paste")
			(net "GND")
		)
		(pad "280" smd rect
			(at 2.050034 56.524906 270)
			(size 0.519938 1.4986)
			(layers "F.Cu" "F.Mask" "F.Paste")
			(net "M_B_CPU0_SB_DQ<27>")
		)
		(pad "281" smd rect
			(at 2.050034 57.375044 270)
			(size 0.519938 1.4986)
			(layers "F.Cu" "F.Mask" "F.Paste")
			(net "GND")
		)
		(pad "282" smd rect
			(at 2.050034 58.224928 270)
			(size 0.519938 1.4986)
			(layers "F.Cu" "F.Mask" "F.Paste")
			(net "M_B_CPU0_SB_DQS_DN<8>")
		)
		(pad "283" smd rect
			(at 2.050034 59.075066 270)
			(size 0.519938 1.4986)
			(layers "F.Cu" "F.Mask" "F.Paste")
			(net "M_B_CPU0_SB_DQS_DP<8>")
		)
		(pad "284" smd rect
			(at 2.050034 59.92495 270)
			(size 0.519938 1.4986)
			(layers "F.Cu" "F.Mask" "F.Paste")
			(net "GND")
		)
		(pad "285" smd rect
			(at 2.050034 60.775088 270)
			(size 0.519938 1.4986)
			(layers "F.Cu" "F.Mask" "F.Paste")
			(net "M_B_CPU0_SB_DQ<30>")
		)
		(pad "286" smd rect
			(at 2.050034 61.624972 270)
			(size 0.519938 1.4986)
			(layers "F.Cu" "F.Mask" "F.Paste")
			(net "GND")
		)
		(pad "287" smd rect
			(at 2.050034 62.47511 270)
			(size 0.519938 1.4986)
			(layers "F.Cu" "F.Mask" "F.Paste")
			(net "M_B_CPU0_SB_DQ<31>")
		)
		(pad "288" smd rect
			(at 2.050034 63.324994 270)
			(size 0.519938 1.4986)
			(layers "F.Cu" "F.Mask" "F.Paste")
			(net "GND")
		)
		(pad "G1" thru_hole oval
			(at 0 -68.97497)
			(size 2.8194 1.5748)
			(drill oval 2.4384 1.1938)
			(layers "*.Cu" "*.Mask")
			(remove_unused_layers no)
			(net "GND")
			(clearance 0.127)
			(thermal_gap 0.127)
		)
		(pad "G2" thru_hole oval
			(at 0 3.875024)
			(size 2.8194 1.5748)
			(drill oval 2.4384 1.1938)
			(layers "*.Cu" "*.Mask")
			(remove_unused_layers no)
			(net "GND")
			(clearance 0.127)
			(thermal_gap 0.127)
		)
		(pad "G3" thru_hole oval
			(at 0 68.97497)
			(size 2.8194 1.5748)
			(drill oval 2.4384 1.1938)
			(layers "*.Cu" "*.Mask")
			(remove_unused_layers no)
			(net "GND")
			(clearance 0.127)
			(thermal_gap 0.127)
		)
	)
)
